# S9S_MB_2U (Grand Teton) — schematic netlist excerpt (pin names and nets, part order shuffled) for the footprints in the layout excerpt that follows; sources: Cadence DE-HDL packaged netlist, KiCad conversion of 03242023_DA0F0TMBIJ0_F0T_Motherboard_J_brd_V01_OCP.brd

R3081  Q_RES  130 1% CHIP  pkg 0402LF  page 256 : A = LED_RST_PLD_CPU0_DRAM_GH_N ; B = P3V3_AUX
C1557  Q_CAP_DIFFBUS  DIFF BUS_0.22UF 6.3V 20% X6S  pkg C0201  page 175 : \1\ = P5E_CPU0_PE4_TX_C_DP<11> ; \2\ = P5E_CPU0_PE4_TX_DP<11>
R4015  Q_RES  100K 1% EMPTY  pkg 0402LF  page 242 : A = P3V3_AUX ; B = HP_LVC3_SCM_HSC_PWRGD

(kicad_pcb
	(version 20260206)
	(generator "pcbnew")
	(generator_version "10.0")
	(general
		(thickness 1.6)
		(legacy_teardrops no)
	)
	(paper "A4")
	(title_block
		(title "03242023_DA0F0TMBIJ0_F0T_Motherboard_J_brd_V01_OCP.brd")
		(comment 1 "Grand Teton / footprints 3700-3702 of 6105")
	)
	(layers
		(0 "F.Cu" signal "TOP")
		(4 "In1.Cu" signal "GND")
		(6 "In2.Cu" signal "IN1")
		(8 "In3.Cu" signal "GND1")
		(10 "In4.Cu" signal "IN2")
		(12 "In5.Cu" signal "GND2")
		(14 "In6.Cu" signal "IN3")
		(16 "In7.Cu" signal "GND3")
		(18 "In8.Cu" signal "VCC")
		(20 "In9.Cu" signal "VCC1")
		(22 "In10.Cu" signal "GND4")
		(24 "In11.Cu" signal "IN4")
		(26 "In12.Cu" signal "GND5")
		(28 "In13.Cu" signal "IN5")
		(30 "In14.Cu" signal "GND6")
		(32 "In15.Cu" signal "IN6")
		(34 "In16.Cu" signal "GND7")
		(2 "B.Cu" signal "BOTTOM")
		(9 "F.Adhes" user "F.Adhesive")
		(11 "B.Adhes" user "B.Adhesive")
		(13 "F.Paste" user "Package Geometry/Pastemask Top")
		(15 "B.Paste" user "Package Geometry/Pastemask Bottom")
		(5 "F.SilkS" user "Ref Des/Silkscreen Top")
		(7 "B.SilkS" user "Ref Des/Silkscreen Bottom")
		(1 "F.Mask" user "Board Geometry/Soldermask Top")
		(3 "B.Mask" user "Board Geometry/Soldermask Bottom")
		(17 "Dwgs.User" user "User.Drawings")
		(19 "Cmts.User" user "User.Comments")
		(21 "Eco1.User" user "User.Eco1")
		(23 "Eco2.User" user "User.Eco2")
		(25 "Edge.Cuts" user "Board Geometry/Outline")
		(27 "Margin" user)
		(31 "F.CrtYd" user "Package Geometry/Place Bound Top")
		(29 "B.CrtYd" user "Package Geometry/Place Bound Bottom")
		(35 "F.Fab" user "Ref Des/Assembly Top")
		(33 "B.Fab" user "Ref Des/Assembly Bottom")
	)
	(footprint ""
		(layer "F.Cu")
		(at 193.089022 -24.091392 -90)
		(property "Reference" "R4015"
			(at 0 0 270)
			(layer "F.SilkS")
			(hide yes)
			(effects
				(font
					(size 1.27 1.27)
				)
			)
		)
		(property "Value" ""
			(at 0 0 270)
			(layer "F.Fab")
			(effects
				(font
					(size 1.27 1.27)
				)
			)
		)
		(duplicate_pad_numbers_are_jumpers no)
		(fp_line
			(start -0.7874 0.4064)
			(end -0.7874 -0.4064)
			(stroke
				(width 0.1524)
				(type default)
			)
			(layer "F.SilkS")
		)
		(fp_line
			(start 0.7874 0.4064)
			(end -0.7874 0.4064)
			(stroke
				(width 0.1524)
				(type default)
			)
			(layer "F.SilkS")
		)
		(fp_line
			(start -0.7874 -0.4064)
			(end 0.7874 -0.4064)
			(stroke
				(width 0.1524)
				(type default)
			)
			(layer "F.SilkS")
		)
		(fp_line
			(start 0.7874 -0.4064)
			(end 0.7874 0.4064)
			(stroke
				(width 0.1524)
				(type default)
			)
			(layer "F.SilkS")
		)
		(fp_line
			(start -0.67945 0.3048)
			(end -0.67945 -0.305054)
			(stroke
				(width 0.1)
				(type default)
			)
			(layer "F.Fab")
		)
		(fp_line
			(start -0.12065 0.3048)
			(end -0.67945 0.3048)
			(stroke
				(width 0.1)
				(type default)
			)
			(layer "F.Fab")
		)
		(fp_line
			(start 0.120396 0.3048)
			(end 0.120396 0.2794)
			(stroke
				(width 0.1)
				(type default)
			)
			(layer "F.Fab")
		)
		(fp_line
			(start 0.67945 0.3048)
			(end 0.120396 0.3048)
			(stroke
				(width 0.1)
				(type default)
			)
			(layer "F.Fab")
		)
		(fp_line
			(start -0.12065 0.2794)
			(end -0.12065 0.3048)
			(stroke
				(width 0.1)
				(type default)
			)
			(layer "F.Fab")
		)
		(fp_line
			(start 0.120396 0.2794)
			(end -0.12065 0.2794)
			(stroke
				(width 0.1)
				(type default)
			)
			(layer "F.Fab")
		)
		(fp_line
			(start -0.12065 -0.2794)
			(end 0.12065 -0.2794)
			(stroke
				(width 0.1)
				(type default)
			)
			(layer "F.Fab")
		)
		(fp_line
			(start 0.12065 -0.2794)
			(end 0.12065 -0.3048)
			(stroke
				(width 0.1)
				(type default)
			)
			(layer "F.Fab")
		)
		(fp_line
			(start 0.12065 -0.3048)
			(end 0.67945 -0.3048)
			(stroke
				(width 0.1)
				(type default)
			)
			(layer "F.Fab")
		)
		(fp_line
			(start 0.67945 -0.3048)
			(end 0.67945 0.3048)
			(stroke
				(width 0.1)
				(type default)
			)
			(layer "F.Fab")
		)
		(fp_line
			(start -0.67945 -0.305054)
			(end -0.12065 -0.305054)
			(stroke
				(width 0.1)
				(type default)
			)
			(layer "F.Fab")
		)
		(fp_line
			(start -0.12065 -0.305054)
			(end -0.12065 -0.2794)
			(stroke
				(width 0.1)
				(type default)
			)
			(layer "F.Fab")
		)
		(pad "1" smd circle
			(at -0.40005 0 270)
			(size 0 0)
			(layers "F.Cu" "F.Mask" "F.Paste")
			(net "P3V3_AUX")
		)
		(pad "2" smd circle
			(at 0.40005 0 270)
			(size 0 0)
			(layers "F.Cu" "F.Mask" "F.Paste")
			(net "HP_LVC3_SCM_HSC_PWRGD")
		)
	)
	(footprint ""
		(layer "F.Cu")
		(at 337.650328 -402.371052 -90)
		(property "Reference" "C1557"
			(at 0 0 270)
			(layer "F.SilkS")
			(hide yes)
			(effects
				(font
					(size 1.27 1.27)
				)
			)
		)
		(property "Value" ""
			(at 0 0 270)
			(layer "F.Fab")
			(effects
				(font
					(size 1.27 1.27)
				)
			)
		)
		(duplicate_pad_numbers_are_jumpers no)
		(fp_line
			(start -0.299974 0.150114)
			(end -0.299974 -0.150114)
			(stroke
				(width 0.1)
				(type default)
			)
			(layer "F.Fab")
		)
		(fp_line
			(start 0.299974 0.150114)
			(end -0.299974 0.150114)
			(stroke
				(width 0.1)
				(type default)
			)
			(layer "F.Fab")
		)
		(fp_line
			(start -0.299974 -0.150114)
			(end 0.299974 -0.150114)
			(stroke
				(width 0.1)
				(type default)
			)
			(layer "F.Fab")
		)
		(fp_line
			(start 0.299974 -0.150114)
			(end 0.299974 0.150114)
			(stroke
				(width 0.1)
				(type default)
			)
			(layer "F.Fab")
		)
		(pad "1" smd rect
			(at -0.2667 0 270)
			(size 0.3048 0.381)
			(layers "F.Cu" "F.Mask" "F.Paste")
			(net "P5E_CPU0_PE4_TX_C_DP<11>")
		)
		(pad "2" smd rect
			(at 0.2667 0 270)
			(size 0.3048 0.381)
			(layers "F.Cu" "F.Mask" "F.Paste")
			(net "P5E_CPU0_PE4_TX_DP<11>")
		)
	)
	(footprint ""
		(layer "F.Cu")
		(at 72.766174 -65.082674 -90)
		(property "Reference" "R3081"
			(at 0 0 270)
			(layer "F.SilkS")
			(hide yes)
			(effects
				(font
					(size 1.27 1.27)
				)
			)
		)
		(property "Value" ""
			(at 0 0 270)
			(layer "F.Fab")
			(effects
				(font
					(size 1.27 1.27)
				)
			)
		)
		(duplicate_pad_numbers_are_jumpers no)
		(fp_line
			(start -0.7874 0.4064)
			(end -0.7874 -0.4064)
			(stroke
				(width 0.1524)
				(type default)
			)
			(layer "F.SilkS")
		)
		(fp_line
			(start 0.7874 0.4064)
			(end -0.7874 0.4064)
			(stroke
				(width 0.1524)
				(type default)
			)
			(layer "F.SilkS")
		)
		(fp_line
			(start -0.7874 -0.4064)
			(end 0.7874 -0.4064)
			(stroke
				(width 0.1524)
				(type default)
			)
			(layer "F.SilkS")
		)
		(fp_line
			(start 0.7874 -0.4064)
			(end 0.7874 0.4064)
			(stroke
				(width 0.1524)
				(type default)
			)
			(layer "F.SilkS")
		)
		(fp_line
			(start -0.67945 0.3048)
			(end -0.67945 -0.305054)
			(stroke
				(width 0.1)
				(type default)
			)
			(layer "F.Fab")
		)
		(fp_line
			(start -0.12065 0.3048)
			(end -0.67945 0.3048)
			(stroke
				(width 0.1)
				(type default)
			)
			(layer "F.Fab")
		)
		(fp_line
			(start 0.120396 0.3048)
			(end 0.120396 0.2794)
			(stroke
				(width 0.1)
				(type default)
			)
			(layer "F.Fab")
		)
		(fp_line
			(start 0.67945 0.3048)
			(end 0.120396 0.3048)
			(stroke
				(width 0.1)
				(type default)
			)
			(layer "F.Fab")
		)
		(fp_line
			(start -0.12065 0.2794)
			(end -0.12065 0.3048)
			(stroke
				(width 0.1)
				(type default)
			)
			(layer "F.Fab")
		)
		(fp_line
			(start 0.120396 0.2794)
			(end -0.12065 0.2794)
			(stroke
				(width 0.1)
				(type default)
			)
			(layer "F.Fab")
		)
		(fp_line
			(start -0.12065 -0.2794)
			(end 0.12065 -0.2794)
			(stroke
				(width 0.1)
				(type default)
			)
			(layer "F.Fab")
		)
		(fp_line
			(start 0.12065 -0.2794)
			(end 0.12065 -0.3048)
			(stroke
				(width 0.1)
				(type default)
			)
			(layer "F.Fab")
		)
		(fp_line
			(start 0.12065 -0.3048)
			(end 0.67945 -0.3048)
			(stroke
				(width 0.1)
				(type default)
			)
			(layer "F.Fab")
		)
		(fp_line
			(start 0.67945 -0.3048)
			(end 0.67945 0.3048)
			(stroke
				(width 0.1)
				(type default)
			)
			(layer "F.Fab")
		)
		(fp_line
			(start -0.67945 -0.305054)
			(end -0.12065 -0.305054)
			(stroke
				(width 0.1)
				(type default)
			)
			(layer "F.Fab")
		)
		(fp_line
			(start -0.12065 -0.305054)
			(end -0.12065 -0.2794)
			(stroke
				(width 0.1)
				(type default)
			)
			(layer "F.Fab")
		)
		(pad "1" smd circle
			(at -0.40005 0 270)
			(size 0 0)
			(layers "F.Cu" "F.Mask" "F.Paste")
			(net "LED_RST_PLD_CPU0_DRAM_GH_N")
		)
		(pad "2" smd circle
			(at 0.40005 0 270)
			(size 0 0)
			(layers "F.Cu" "F.Mask" "F.Paste")
			(net "P3V3_AUX")
		)
	)
)
